(kicad_pcb
	(version 20240108)
	(generator "pcbnew")
	(generator_version "8.0")
	(general
		(thickness 1.62)
		(legacy_teardrops no)
	)
	(paper "A4")
	(title_block
		(title "Jetson Orin Baseboard")
		(date "2025-03-12")
		(rev "1.3.4")
		(company "Antmicro Ltd")
		(comment 1 "www.antmicro.com")
		(comment 9 "footprints 240-243 of 677")
	)
	(layers
		(0 "F.Cu" signal)
		(1 "In1.Cu" signal)
		(2 "In2.Cu" signal)
		(3 "In3.Cu" signal)
		(4 "In4.Cu" jumper)
		(5 "In5.Cu" signal)
		(6 "In6.Cu" signal)
		(31 "B.Cu" signal)
		(32 "B.Adhes" user "B.Adhesive")
		(33 "F.Adhes" user "F.Adhesive")
		(34 "B.Paste" user)
		(35 "F.Paste" user)
		(36 "B.SilkS" user "B.Silkscreen")
		(37 "F.SilkS" user "F.Silkscreen")
		(38 "B.Mask" user)
		(39 "F.Mask" user)
		(40 "Dwgs.User" user "User.Drawings")
		(41 "Cmts.User" user "User.Comments")
		(42 "Eco1.User" user "User.Eco1")
		(43 "Eco2.User" user "User.Eco2")
		(44 "Edge.Cuts" user)
		(45 "Margin" user)
		(46 "B.CrtYd" user "B.Courtyard")
		(47 "F.CrtYd" user "F.Courtyard")
		(48 "B.Fab" user)
		(49 "F.Fab" user)
	)
	(footprint "antmicro-footprints:R_0402_1005Metric"
		(layer "F.Cu")
		(at 57.51 92.77)
		(descr "Resistor SMD 0402")
		(tags "resistor SMD 0402")
		(property "Reference" "R272"
			(at 27.89 1.265 180)
			(layer "F.SilkS")
			(effects
				(font
					(size 0.7 0.7)
					(thickness 0.15)
				)
				(justify left bottom)
			)
		)
		(property "Value" "R_470k_0402"
			(at -1.011843 1.772047 0)
			(layer "F.Fab")
			(effects
				(font
					(size 0.7 0.7)
					(thickness 0.15)
				)
				(justify left bottom)
			)
		)
		(property "Footprint" "antmicro-footprints:R_0402_1005Metric"
			(at 0 0 0)
			(layer "F.Fab")
			(hide yes)
			(effects
				(font
					(size 1.27 1.27)
					(thickness 0.15)
				)
			)
		)
		(property "Datasheet" "https://www.bourns.com/docs/product-datasheets/cr.pdf"
			(at 0 0 0)
			(layer "F.Fab")
			(hide yes)
			(effects
				(font
					(size 1.27 1.27)
					(thickness 0.15)
				)
			)
		)
		(property "Description" "SMD Chip Resistor, 470 kohm, ± 1%, 62.5 mW, 0402 [1005 Metric], Thick Film, Sulfur Resistant"
			(at 0 0 0)
			(layer "F.Fab")
			(hide yes)
			(effects
				(font
					(size 1.27 1.27)
					(thickness 0.15)
				)
			)
		)
		(property "MPN" "CR0402-FX-4703GLF"
			(at 0 0 0)
			(unlocked yes)
			(layer "F.Fab")
			(hide yes)
			(effects
				(font
					(size 1 1)
					(thickness 0.15)
				)
			)
		)
		(property "Manufacturer" "Bourns"
			(at 0 0 0)
			(unlocked yes)
			(layer "F.Fab")
			(hide yes)
			(effects
				(font
					(size 1 1)
					(thickness 0.15)
				)
			)
		)
		(property "License" "Apache-2.0"
			(at 0 0 0)
			(unlocked yes)
			(layer "F.Fab")
			(hide yes)
			(effects
				(font
					(size 1 1)
					(thickness 0.15)
				)
			)
		)
		(property "Author" "Antmicro"
			(at 0 0 0)
			(unlocked yes)
			(layer "F.Fab")
			(hide yes)
			(effects
				(font
					(size 1 1)
					(thickness 0.15)
				)
			)
		)
		(property "Val" "470k"
			(at 0 0 0)
			(unlocked yes)
			(layer "F.Fab")
			(hide yes)
			(effects
				(font
					(size 1 1)
					(thickness 0.15)
				)
			)
		)
		(property "Tolerance" "1%"
			(at 0 0 0)
			(unlocked yes)
			(layer "F.Fab")
			(hide yes)
			(effects
				(font
					(size 1 1)
					(thickness 0.15)
				)
			)
		)
		(sheetname "Supply")
		(sheetfile "supply.kicad_sch")
		(attr smd)
		(fp_rect
			(start -0.925 -0.47)
			(end 0.925 0.47)
			(stroke
				(width 0.05)
				(type default)
			)
			(fill none)
			(layer "F.CrtYd")
		)
		(fp_rect
			(start -0.5 -0.25)
			(end 0.5 0.25)
			(stroke
				(width 0.15)
				(type solid)
			)
			(fill none)
			(layer "F.Fab")
		)
		(fp_text user "License: Apache-2.0"
			(at -0.95 5.169 0)
			(layer "F.Fab")
			(hide yes)
			(effects
				(font
					(size 0.7 0.7)
					(thickness 0.15)
				)
				(justify left bottom)
			)
		)
		(fp_text user "Author: Antmicro"
			(at -0.95 4.169 0)
			(layer "F.Fab")
			(hide yes)
			(effects
				(font
					(size 0.7 0.7)
					(thickness 0.15)
				)
				(justify left bottom)
			)
		)
		(fp_text user "${REFERENCE}"
			(at -0.95 3.168 0)
			(layer "F.Fab")
			(hide yes)
			(effects
				(font
					(size 0.7 0.7)
					(thickness 0.15)
				)
				(justify left bottom)
			)
		)
		(pad "1" smd roundrect
			(at -0.48 0)
			(size 0.59 0.64)
			(layers "F.Cu" "F.Paste" "F.Mask")
			(roundrect_rratio 0.25)
			(net 787 "+5V_SoM")
			(pintype "passive")
		)
		(pad "2" smd roundrect
			(at 0.48 0)
			(size 0.59 0.64)
			(layers "F.Cu" "F.Paste" "F.Mask")
			(roundrect_rratio 0.25)
			(net 792 "Net-(U29-PG)")
			(pintype "passive")
		)
	)
	(footprint "antmicro-footprints:R_0402_1005Metric"
		(layer "F.Cu")
		(at 132.085 119.7)
		(descr "Resistor SMD 0402")
		(tags "resistor SMD 0402")
		(property "Reference" "R230"
			(at -1.735 -0.45 0)
			(layer "F.SilkS")
			(effects
				(font
					(size 0.7 0.7)
					(thickness 0.15)
				)
				(justify left bottom)
			)
		)
		(property "Value" "R_100k_0402"
			(at 0 1.4 0)
			(layer "F.Fab")
			(effects
				(font
					(size 0.7 0.7)
					(thickness 0.15)
				)
				(justify left bottom)
			)
		)
		(property "Footprint" "antmicro-footprints:R_0402_1005Metric"
			(at 0 0 0)
			(layer "F.Fab")
			(hide yes)
			(effects
				(font
					(size 1.27 1.27)
					(thickness 0.15)
				)
			)
		)
		(property "Datasheet" "https://www.bourns.com/docs/product-datasheets/cr.pdf"
			(at 0 0 0)
			(layer "F.Fab")
			(hide yes)
			(effects
				(font
					(size 1.27 1.27)
					(thickness 0.15)
				)
			)
		)
		(property "Author" "Antmicro"
			(at 0 0 0)
			(layer "F.Fab")
			(hide yes)
			(effects
				(font
					(size 1 1)
					(thickness 0.15)
				)
			)
		)
		(property "License" "Apache-2.0"
			(at 0 0 0)
			(layer "F.Fab")
			(hide yes)
			(effects
				(font
					(size 1 1)
					(thickness 0.15)
				)
			)
		)
		(property "MPN" "CR0402-FX-1003GLF"
			(at 0 0 0)
			(layer "F.Fab")
			(hide yes)
			(effects
				(font
					(size 1 1)
					(thickness 0.15)
				)
			)
		)
		(property "Manufacturer" "Bourns"
			(at 0 0 0)
			(layer "F.Fab")
			(hide yes)
			(effects
				(font
					(size 1 1)
					(thickness 0.15)
				)
			)
		)
		(property "Tolerance" "1%"
			(at 0 0 0)
			(layer "F.Fab")
			(hide yes)
			(effects
				(font
					(size 1 1)
					(thickness 0.15)
				)
			)
		)
		(property "Val" "100k"
			(at 0 0 0)
			(layer "F.Fab")
			(hide yes)
			(effects
				(font
					(size 1 1)
					(thickness 0.15)
				)
			)
		)
		(sheetname "Peripherals")
		(sheetfile "peripherals.kicad_sch")
		(attr smd)
		(fp_rect
			(start -0.925 -0.47)
			(end 0.925 0.47)
			(stroke
				(width 0.05)
				(type default)
			)
			(fill none)
			(layer "F.CrtYd")
		)
		(fp_rect
			(start -0.5 -0.25)
			(end 0.5 0.25)
			(stroke
				(width 0.15)
				(type solid)
			)
			(fill none)
			(layer "F.Fab")
		)
		(fp_text user "Author: Antmicro"
			(at -0.95 4.169 0)
			(layer "F.Fab")
			(hide yes)
			(effects
				(font
					(size 0.7 0.7)
					(thickness 0.15)
				)
				(justify left bottom)
			)
		)
		(fp_text user "${REFERENCE}"
			(at -0.95 3.168 0)
			(layer "F.Fab")
			(hide yes)
			(effects
				(font
					(size 0.7 0.7)
					(thickness 0.15)
				)
				(justify left bottom)
			)
		)
		(fp_text user "License: Apache-2.0"
			(at -0.95 5.169 0)
			(layer "F.Fab")
			(hide yes)
			(effects
				(font
					(size 0.7 0.7)
					(thickness 0.15)
				)
				(justify left bottom)
			)
		)
		(pad "1" smd roundrect
			(at -0.48 0)
			(size 0.59 0.64)
			(layers "F.Cu" "F.Paste" "F.Mask")
			(roundrect_rratio 0.25)
			(net 1 "GND")
			(pintype "passive")
		)
		(pad "2" smd roundrect
			(at 0.48 0)
			(size 0.59 0.64)
			(layers "F.Cu" "F.Paste" "F.Mask")
			(roundrect_rratio 0.25)
			(net 44 "USER_LED1")
			(pintype "passive")
		)
	)
	(footprint "antmicro-footprints:R_0402_1005Metric"
		(layer "F.Cu")
		(at 80.7 112.8 180)
		(descr "Resistor SMD 0402")
		(tags "resistor SMD 0402")
		(property "Reference" "R131"
			(at -1.7 0.6 0)
			(layer "F.SilkS")
			(effects
				(font
					(size 0.7 0.7)
					(thickness 0.15)
				)
				(justify right bottom)
			)
		)
		(property "Value" "R_10k_0402"
			(at 0 1.4 0)
			(layer "F.Fab")
			(effects
				(font
					(size 0.7 0.7)
					(thickness 0.15)
				)
				(justify right bottom)
			)
		)
		(property "Footprint" "antmicro-footprints:R_0402_1005Metric"
			(at 0 0 180)
			(layer "F.Fab")
			(hide yes)
			(effects
				(font
					(size 1.27 1.27)
					(thickness 0.15)
				)
			)
		)
		(property "Datasheet" "https://www.bourns.com/docs/product-datasheets/cr.pdf"
			(at 0 0 180)
			(layer "F.Fab")
			(hide yes)
			(effects
				(font
					(size 1.27 1.27)
					(thickness 0.15)
				)
			)
		)
		(property "Author" "Antmicro"
			(at 161.4 225.6 0)
			(layer "F.Fab")
			(hide yes)
			(effects
				(font
					(size 1 1)
					(thickness 0.15)
				)
			)
		)
		(property "License" "Apache-2.0"
			(at 161.4 225.6 0)
			(layer "F.Fab")
			(hide yes)
			(effects
				(font
					(size 1 1)
					(thickness 0.15)
				)
			)
		)
		(property "MPN" "CR0402-FX-1002GLF"
			(at 161.4 225.6 0)
			(layer "F.Fab")
			(hide yes)
			(effects
				(font
					(size 1 1)
					(thickness 0.15)
				)
			)
		)
		(property "Manufacturer" "Bourns"
			(at 161.4 225.6 0)
			(layer "F.Fab")
			(hide yes)
			(effects
				(font
					(size 1 1)
					(thickness 0.15)
				)
			)
		)
		(property "Tolerance" "1%"
			(at 161.4 225.6 0)
			(layer "F.Fab")
			(hide yes)
			(effects
				(font
					(size 1 1)
					(thickness 0.15)
				)
			)
		)
		(property "Val" "10k"
			(at 161.4 225.6 0)
			(layer "F.Fab")
			(hide yes)
			(effects
				(font
					(size 1 1)
					(thickness 0.15)
				)
			)
		)
		(sheetname "USB Debug, DP")
		(sheetfile "usb.kicad_sch")
		(attr smd)
		(fp_rect
			(start -0.925 -0.47)
			(end 0.925 0.47)
			(stroke
				(width 0.05)
				(type default)
			)
			(fill none)
			(layer "F.CrtYd")
		)
		(fp_rect
			(start -0.5 -0.25)
			(end 0.5 0.25)
			(stroke
				(width 0.15)
				(type solid)
			)
			(fill none)
			(layer "F.Fab")
		)
		(fp_text user "License: Apache-2.0"
			(at -0.95 5.169 0)
			(layer "F.Fab")
			(hide yes)
			(effects
				(font
					(size 0.7 0.7)
					(thickness 0.15)
				)
				(justify right bottom)
			)
		)
		(fp_text user "${REFERENCE}"
			(at -0.95 3.168 0)
			(layer "F.Fab")
			(hide yes)
			(effects
				(font
					(size 0.7 0.7)
					(thickness 0.15)
				)
				(justify right bottom)
			)
		)
		(fp_text user "Author: Antmicro"
			(at -0.95 4.169 0)
			(layer "F.Fab")
			(hide yes)
			(effects
				(font
					(size 0.7 0.7)
					(thickness 0.15)
				)
				(justify right bottom)
			)
		)
		(pad "1" smd roundrect
			(at -0.48 0 180)
			(size 0.59 0.64)
			(layers "F.Cu" "F.Paste" "F.Mask")
			(roundrect_rratio 0.25)
			(net 255 "PDC_MISO")
			(pintype "passive")
		)
		(pad "2" smd roundrect
			(at 0.48 0 180)
			(size 0.59 0.64)
			(layers "F.Cu" "F.Paste" "F.Mask")
			(roundrect_rratio 0.25)
			(net 98 "EEPROM_PWR")
			(pintype "passive")
		)
	)
	(footprint "antmicro-footprints:Fiducial_1mm_Mask2mm"
		(layer "F.Cu")
		(at 32.3 127.15)
		(descr "Circular Fiducial, 1mm bare copper, 3mm soldermask opening")
		(tags "fiducial")
		(property "Reference" "FID1"
			(at 0 -1.4 0)
			(layer "F.SilkS")
			(hide yes)
			(effects
				(font
					(size 0.7 0.7)
					(thickness 0.15)
				)
				(justify left bottom)
			)
		)
		(property "Value" "Fiducial_1mm_Mask2mm"
			(at 0 2.2 0)
			(layer "F.Fab")
			(effects
				(font
					(size 0.7 0.7)
					(thickness 0.15)
				)
				(justify left bottom)
			)
		)
		(property "Footprint" "antmicro-footprints:Fiducial_1mm_Mask2mm"
			(at 0 0 0)
			(layer "F.Fab")
			(hide yes)
			(effects
				(font
					(size 1.27 1.27)
					(thickness 0.15)
				)
			)
		)
		(attr board_only exclude_from_pos_files exclude_from_bom)
		(fp_circle
			(center 0 0)
			(end 1.24 0)
			(stroke
				(width 0.05)
				(type solid)
			)
			(fill none)
			(layer "F.CrtYd")
		)
		(fp_circle
			(center 0 0)
			(end 0.999 0)
			(stroke
				(width 0.15)
				(type solid)
			)
			(fill none)
			(layer "F.Fab")
		)
		(fp_text user "License: Apache-2.0"
			(at -1.25 7.003 0)
			(layer "F.Fab")
			(hide yes)
			(effects
				(font
					(size 0.7 0.7)
					(thickness 0.15)
				)
				(justify left bottom)
			)
		)
		(fp_text user "Author: Antmicro"
			(at -1.25 5.803 0)
			(layer "F.Fab")
			(hide yes)
			(effects
				(font
					(size 0.7 0.7)
					(thickness 0.15)
				)
				(justify left bottom)
			)
		)
		(fp_text user "${REFERENCE}"
			(at -1.25 4.603 0)
			(layer "F.Fab")
			(hide yes)
			(effects
				(font
					(size 0.7 0.7)
					(thickness 0.15)
				)
				(justify left bottom)
			)
		)
		(pad "" smd circle
			(at 0 0)
			(size 1 1)
			(layers "F.Cu" "F.Mask")
			(solder_mask_margin 0.5)
			(clearance 0.5)
		)
	)
)
